# S9S_MB_2U (Grand Teton) — schematic netlist excerpt (pin names and nets, part order shuffled) for the footprints in the layout excerpt that follows; sources: Cadence DE-HDL packaged netlist, KiCad conversion of 03242023_DA0F0TMBIJ0_F0T_Motherboard_J_brd_V01_OCP.brd

J15  SCONN288_ADR50017P130CC  SCONN288_ADR50017-P130CC IO  pkg DDR288S_1-1VXB  page 96
  VIN_BULK0  = P12V_S3_AUX_CPU0_NVDIMM
  RFU0  = TP_CHH_CPU0_DIMM1_FRU_0
  VIN_MGMT  = P3V3_AUX
  HSCL  = I3C_SPD_DDREFGH_CPU0_LVC1_SCL_6
  HSDA  = I3C_SPD_DDREFGH_CPU0_LVC1_SDA
  VSS0  = GND
  DQ0_A  = M_H_CPU0_SA_DQ<0>
  VSS1  = GND
  DQ1_A  = M_H_CPU0_SA_DQ<1>
  VSS2  = GND
  DQS0_A_T  = M_H_CPU0_SA_DQS_DP<0>
  DQS0_A_C  = M_H_CPU0_SA_DQS_DN<0>
  VSS3  = GND
  DQ4_A  = M_H_CPU0_SA_DQ<4>
  VSS4  = GND
  DQ5_A  = M_H_CPU0_SA_DQ<5>
  VSS5  = GND
  DQ8_A  = M_H_CPU0_SA_DQ<8>
  VSS6  = GND
  DQ9_A  = M_H_CPU0_SA_DQ<9>
  VSS7  = GND
  DQS1_A_T  = M_H_CPU0_SA_DQS_DP<1>
  DQS1_A_C  = M_H_CPU0_SA_DQS_DN<1>
  VSS8  = GND
  DQ12_A  = M_H_CPU0_SA_DQ<12>
  VSS9  = GND
  DQ13_A  = M_H_CPU0_SA_DQ<13>
  VSS10  = GND
  DQ16_A  = M_H_CPU0_SA_DQ<16>
  VSS11  = GND
  DQ17_A  = M_H_CPU0_SA_DQ<17>
  VSS12  = GND
  DQS2_A_T  = M_H_CPU0_SA_DQS_DP<2>
  DQS2_A_C  = M_H_CPU0_SA_DQS_DN<2>
  VSS13  = GND
  DQ20_A  = M_H_CPU0_SA_DQ<20>
  VSS14  = GND
  DQ21_A  = M_H_CPU0_SA_DQ<21>
  VSS15  = GND
  DQ24_A  = M_H_CPU0_SA_DQ<24>
  VSS16  = GND
  DQ25_A  = M_H_CPU0_SA_DQ<25>
  VSS17  = GND
  DQS3_A_T  = M_H_CPU0_SA_DQS_DP<3>
  DQS3_A_C  = M_H_CPU0_SA_DQS_DN<3>
  VSS18  = GND
  DQ28_A  = M_H_CPU0_SA_DQ<28>
  VSS19  = GND
  DQ29_A  = M_H_CPU0_SA_DQ<29>
  VSS20  = GND
  CB0_A  = M_H_CPU0_SA_CB<0>
  VSS21  = GND
  CB1_A  = M_H_CPU0_SA_CB<1>
  VSS22  = GND
  DQS4_A_T  = M_H_CPU0_SA_DQS_DP<4>
  DQS4_A_C  = M_H_CPU0_SA_DQS_DN<4>
  VSS23  = GND
  CB4_A  = M_H_CPU0_SA_CB<4>
  VSS24  = GND
  CB5_A  = M_H_CPU0_SA_CB<5>
  VSS25  = GND
  ALERT_N  = M_H_CPU0_ALERT_N
  VSS26  = GND
  CS0_A_N  = M_H_CPU0_SA_CS_N<0>
  VSS27  = GND
  CA0_A  = M_H_CPU0_SA_CA<0>
  VSS28  = GND
  CA2_A  = M_H_CPU0_SA_CA<2>
  VSS29  = GND
  CA4_A  = M_H_CPU0_SA_CA<4>
  VSS30  = GND
  CA6_A  = M_H_CPU0_SA_CA<6>
  VSS31  = GND
  PAR_A  = M_H_CPU0_SA_PAR
  VSS32  = GND
  CA0_B  = M_H_CPU0_SB_CA<0>
  VSS33  = GND
  CA2_B  = M_H_CPU0_SB_CA<2>
  VSS34  = GND
  CA4_B  = M_H_CPU0_SB_CA<4>
  VSS35  = GND
  CA6_B  = M_H_CPU0_SB_CA<6>
  VSS36  = GND
  CS0_B_N  = M_H_CPU0_SB_CS_N<0>
  VSS37  = GND
  \lbd||rsp_a_n\  = M_H_CPU0_SA_RSP<0>
  \lbs||rsp_b_n\  = M_H_CPU0_SB_RSP<0>
  VSS38  = GND
  CB4_B  = M_H_CPU0_SB_CB<4>
  VSS39  = GND
  CB5_B  = M_H_CPU0_SB_CB<5>
  VSS40  = GND
  \dqs9_b_t||tdqs9_b_t||dbi4_b_n\  = M_H_CPU0_SB_DQS_DP<9>
  \dqs9_b_c||tdqs9_b_c\  = M_H_CPU0_SB_DQS_DN<9>
  VSS41  = GND
  CB0_B  = M_H_CPU0_SB_CB<0>
  VSS42  = GND
  CB1_B  = M_H_CPU0_SB_CB<1>
  VSS43  = GND
  DQ0_B  = M_H_CPU0_SB_DQ<0>
  VSS44  = GND
  DQ1_B  = M_H_CPU0_SB_DQ<1>
  VSS45  = GND
  DQS0_B_T  = M_H_CPU0_SB_DQS_DP<0>
  DQS0_B_C  = M_H_CPU0_SB_DQS_DN<0>
  VSS46  = GND
  DQ4_B  = M_H_CPU0_SB_DQ<4>
  VSS47  = GND
  DQ5_B  = M_H_CPU0_SB_DQ<5>
  VSS48  = GND
  DQ8_B  = M_H_CPU0_SB_DQ<8>
  VSS49  = GND
  DQ9_B  = M_H_CPU0_SB_DQ<9>
  VSS50  = GND
  DQS1_B_T  = M_H_CPU0_SB_DQS_DP<1>
  DQS1_B_C  = M_H_CPU0_SB_DQS_DN<1>
  VSS51  = GND
  DQ12_B  = M_H_CPU0_SB_DQ<12>
  VSS52  = GND
  DQ13_B  = M_H_CPU0_SB_DQ<13>
  VSS53  = GND
  DQ16_B  = M_H_CPU0_SB_DQ<16>
  VSS54  = GND
  DQ17_B  = M_H_CPU0_SB_DQ<17>
  VSS55  = GND
  DQS2_B_T  = M_H_CPU0_SB_DQS_DP<2>
  DQS2_B_C  = M_H_CPU0_SB_DQS_DN<2>
  VSS56  = GND
  DQ20_B  = M_H_CPU0_SB_DQ<20>
  VSS57  = GND
  DQ21_B  = M_H_CPU0_SB_DQ<21>
  VSS58  = GND
  DQ24_B  = M_H_CPU0_SB_DQ<24>
  VSS59  = GND
  DQ25_B  = M_H_CPU0_SB_DQ<25>
  VSS60  = GND
  DQS3_B_T  = M_H_CPU0_SB_DQS_DP<3>
  DQS3_B_C  = M_H_CPU0_SB_DQS_DN<3>
  VSS61  = GND
  DQ28_B  = M_H_CPU0_SB_DQ<28>
  VSS62  = GND
  DQ29_B  = M_H_CPU0_SB_DQ<29>
  VSS63  = GND
  RFU1  = TP_CHH_CPU0_DIMM1_FRU_1
  VIN_BULK1  = P12V_S3_AUX_CPU0_NVDIMM
  VIN_BULK2  = P12V_S3_AUX_CPU0_NVDIMM
  \pwr_good||fail_n\  = PWRGD_CHH_CPU0_DIMM1
  HSA  = PD_CHH_CPU0_DIMM1_SAA
  RFU2  = TP_CHH_CPU0_DIMM1_FRU_2
  RFU3  = TP_CHH_CPU0_DIMM1_FRU_3
  VSS64  = GND
  DQ2_A  = M_H_CPU0_SA_DQ<2>
  VSS65  = GND
  DQ3_A  = M_H_CPU0_SA_DQ<3>
  VSS66  = GND
  \dqs5_a_c||tdqs5_a_c||dqs5_a_t||tdqs5_a_t\  = M_H_CPU0_SA_DQS_DN<5>
  \dqs5_a_t||tdqs5_a_t\  = M_H_CPU0_SA_DQS_DP<5>
  VSS67  = GND
  DQ6_A  = M_H_CPU0_SA_DQ<6>
  VSS68  = GND
  DQ7_A  = M_H_CPU0_SA_DQ<7>
  VSS69  = GND
  DQ10_A  = M_H_CPU0_SA_DQ<10>
  VSS70  = GND
  DQ11_A  = M_H_CPU0_SA_DQ<11>
  VSS71  = GND
  \dqs6_a_c||tdqs6_a_c||dqs6_a_t||tdqs6_a_t\  = M_H_CPU0_SA_DQS_DN<6>
  \dqs6_a_t||tdqs6_a_t\  = M_H_CPU0_SA_DQS_DP<6>
  VSS72  = GND
  DQ14_A  = M_H_CPU0_SA_DQ<14>
  VSS73  = GND
  DQ15_A  = M_H_CPU0_SA_DQ<15>
  VSS74  = GND
  DQ18_A  = M_H_CPU0_SA_DQ<18>
  VSS75  = GND
  DQ19_A  = M_H_CPU0_SA_DQ<19>
  VSS76  = GND
  \dqs7_a_c||tdqs7_a_c\  = M_H_CPU0_SA_DQS_DN<7>
  \dqs7_a_t||tdqs7_a_t\  = M_H_CPU0_SA_DQS_DP<7>
  VSS77  = GND
  DQ22_A  = M_H_CPU0_SA_DQ<22>
  VSS78  = GND
  DQ23_A  = M_H_CPU0_SA_DQ<23>
  VSS79  = GND
  DQ26_A  = M_H_CPU0_SA_DQ<26>
  VSS80  = GND
  DQ27_A  = M_H_CPU0_SA_DQ<27>
  VSS81  = GND
  \dqs8_a_c||tdqs8_a_c\  = M_H_CPU0_SA_DQS_DN<8>
  \dqs8_a_t||tdqs8_a_t\  = M_H_CPU0_SA_DQS_DP<8>
  VSS82  = GND
  DQ30_A  = M_H_CPU0_SA_DQ<30>
  VSS83  = GND
  DQ31_A  = M_H_CPU0_SA_DQ<31>
  VSS84  = GND
  CB2_A  = M_H_CPU0_SA_CB<2>
  VSS85  = GND
  CB3_A  = M_H_CPU0_SA_CB<3>
  VSS86  = GND
  \dqs9_a_c||tdqs9_a_c\  = M_H_CPU0_SA_DQS_DN<9>
  \dqs9_a_t||tdqs9_a_t\  = M_H_CPU0_SA_DQS_DP<9>
  VSS87  = GND
  CB6_A  = M_H_CPU0_SA_CB<6>
  VSS88  = GND
  CB7_A  = M_H_CPU0_SA_CB<7>
  VSS89  = GND
  RESET_N  = RST_M_GH_CPU0_FPGA_N
  VSS90  = GND
  CS1_A_N  = M_H_CPU0_SA_CS_N<1>
  VSS91  = GND
  CA1_A  = M_H_CPU0_SA_CA<1>
  VSS92  = GND
  CA3_A  = M_H_CPU0_SA_CA<3>
  VSS93  = GND
  CA5_A  = M_H_CPU0_SA_CA<5>
  VSS94  = GND
  CK_T  = M_H_CPU0_CLK_DP<0>
  CK_C  = M_H_CPU0_CLK_DN<0>
  VSS95  = GND
  RFU4  = TP_CHH_CPU0_DIMM1_FRU_4
  CA1_B  = M_H_CPU0_SB_CA<1>
  VSS96  = GND
  CA3_B  = M_H_CPU0_SB_CA<3>
  VSS97  = GND
  CA5_B  = M_H_CPU0_SB_CA<5>
  VSS98  = GND
  PAR_B  = M_H_CPU0_SB_PAR
  VSS99  = GND
  CS1_B_N  = M_H_CPU0_SB_CS_N<1>
  VSS100  = GND
  RFU5  = TP_CHH_CPU0_DIMM1_FRU_5
  RFU6  = TP_CHH_CPU0_DIMM1_FRU_6
  VSS101  = GND
  CB6_B  = M_H_CPU0_SB_CB<6>
  VSS102  = GND
  CB7_B  = M_H_CPU0_SB_CB<7>
  VSS103  = GND
  DQS4_B_C  = M_H_CPU0_SB_DQS_DN<4>
  DQS4_B_T  = M_H_CPU0_SB_DQS_DP<4>
  VSS104  = GND
  CB2_B  = M_H_CPU0_SB_CB<2>
  VSS105  = GND
  CB3_B  = M_H_CPU0_SB_CB<3>
  VSS106  = GND
  DQ2_B  = M_H_CPU0_SB_DQ<2>
  VSS107  = GND
  DQ3_B  = M_H_CPU0_SB_DQ<3>
  VSS108  = GND
  \dqs5_b_c||tdqs5_b_c\  = M_H_CPU0_SB_DQS_DN<5>
  \dqs5_b_t||tdqs5_b_t\  = M_H_CPU0_SB_DQS_DP<5>
  VSS109  = GND
  DQ6_B  = M_H_CPU0_SB_DQ<6>
  VSS110  = GND
  DQ7_B  = M_H_CPU0_SB_DQ<7>
  VSS111  = GND
  DQ10_B  = M_H_CPU0_SB_DQ<10>
  VSS112  = GND
  DQ11_B  = M_H_CPU0_SB_DQ<11>
  VSS113  = GND
  \dqs6_b_c||tdqs6_b_c\  = M_H_CPU0_SB_DQS_DN<6>
  \dqs6_b_t||tdqs6_b_t\  = M_H_CPU0_SB_DQS_DP<6>
  VSS114  = GND
  DQ14_B  = M_H_CPU0_SB_DQ<14>
  VSS115  = GND
  DQ15_B  = M_H_CPU0_SB_DQ<15>
  VSS116  = GND
  DQ18_B  = M_H_CPU0_SB_DQ<18>
  VSS117  = GND
  DQ19_B  = M_H_CPU0_SB_DQ<19>
  VSS118  = GND
  \dqs7_b_c||tdqs7_b_c\  = M_H_CPU0_SB_DQS_DN<7>
  \dqs7_b_t||tdqs7_b_t\  = M_H_CPU0_SB_DQS_DP<7>
  VSS119  = GND
  DQ22_B  = M_H_CPU0_SB_DQ<22>
  VSS120  = GND
  DQ23_B  = M_H_CPU0_SB_DQ<23>
  VSS121  = GND
  DQ26_B  = M_H_CPU0_SB_DQ<26>
  VSS122  = GND
  DQ27_B  = M_H_CPU0_SB_DQ<27>
  VSS123  = GND
  \dqs8_b_c||tdqs8_b_c\  = M_H_CPU0_SB_DQS_DN<8>
  \dqs8_b_t||tdqs8_b_t\  = M_H_CPU0_SB_DQS_DP<8>
  VSS124  = GND
  DQ30_B  = M_H_CPU0_SB_DQ<30>
  VSS125  = GND
  DQ31_B  = M_H_CPU0_SB_DQ<31>
  VSS126  = GND
  G1  = GND
  G2  = GND
  G3  = GND

(kicad_pcb
	(version 20260206)
	(generator "pcbnew")
	(generator_version "10.0")
	(general
		(thickness 1.6)
		(legacy_teardrops no)
	)
	(paper "A4")
	(title_block
		(title "03242023_DA0F0TMBIJ0_F0T_Motherboard_J_brd_V01_OCP.brd")
		(comment 1 "Grand Teton / footprint 2194 of 6105 (J15), pads 275-291 of 291")
	)
	(layers
		(0 "F.Cu" signal "TOP")
		(4 "In1.Cu" signal "GND")
		(6 "In2.Cu" signal "IN1")
		(8 "In3.Cu" signal "GND1")
		(10 "In4.Cu" signal "IN2")
		(12 "In5.Cu" signal "GND2")
		(14 "In6.Cu" signal "IN3")
		(16 "In7.Cu" signal "GND3")
		(18 "In8.Cu" signal "VCC")
		(20 "In9.Cu" signal "VCC1")
		(22 "In10.Cu" signal "GND4")
		(24 "In11.Cu" signal "IN4")
		(26 "In12.Cu" signal "GND5")
		(28 "In13.Cu" signal "IN5")
		(30 "In14.Cu" signal "GND6")
		(32 "In15.Cu" signal "IN6")
		(34 "In16.Cu" signal "GND7")
		(2 "B.Cu" signal "BOTTOM")
		(9 "F.Adhes" user "F.Adhesive")
		(11 "B.Adhes" user "B.Adhesive")
		(13 "F.Paste" user "Package Geometry/Pastemask Top")
		(15 "B.Paste" user "Package Geometry/Pastemask Bottom")
		(5 "F.SilkS" user "Ref Des/Silkscreen Top")
		(7 "B.SilkS" user "Ref Des/Silkscreen Bottom")
		(1 "F.Mask" user "Board Geometry/Soldermask Top")
		(3 "B.Mask" user "Board Geometry/Soldermask Bottom")
		(17 "Dwgs.User" user "User.Drawings")
		(19 "Cmts.User" user "User.Comments")
		(21 "Eco1.User" user "User.Eco1")
		(23 "Eco2.User" user "User.Eco2")
		(25 "Edge.Cuts" user "Board Geometry/Outline")
		(27 "Margin" user)
		(31 "F.CrtYd" user "Package Geometry/Place Bound Top")
		(29 "B.CrtYd" user "Package Geometry/Place Bound Bottom")
		(35 "F.Fab" user "Ref Des/Assembly Top")
		(33 "B.Fab" user "Ref Des/Assembly Bottom")
	)
	(footprint ""
		(layer "F.Cu")
		(at 461.609948 -258.091686)
		(property "Reference" "J15"
			(at 3.019552 -81.652872 0)
			(unlocked yes)
			(layer "F.SilkS")
			(effects
				(font
					(size 0.7874 0.5842)
					(thickness 0.1524)
				)
				(justify left)
			)
		)
		(property "Value" ""
			(at 0 0 0)
			(layer "F.Fab")
			(effects
				(font
					(size 1.27 1.27)
				)
			)
		)
		(duplicate_pad_numbers_are_jumpers no)
		(pad "275" smd rect
			(at 2.050034 52.274978 270)
			(size 0.519938 1.4986)
			(layers "F.Cu" "F.Mask" "F.Paste")
			(net "GND")
		)
		(pad "276" smd rect
			(at 2.050034 53.125116 270)
			(size 0.519938 1.4986)
			(layers "F.Cu" "F.Mask" "F.Paste")
			(net "M_H_CPU0_SB_DQ<23>")
		)
		(pad "277" smd rect
			(at 2.050034 53.975 270)
			(size 0.519938 1.4986)
			(layers "F.Cu" "F.Mask" "F.Paste")
			(net "GND")
		)
		(pad "278" smd rect
			(at 2.050034 54.824884 270)
			(size 0.519938 1.4986)
			(layers "F.Cu" "F.Mask" "F.Paste")
			(net "M_H_CPU0_SB_DQ<26>")
		)
		(pad "279" smd rect
			(at 2.050034 55.675022 270)
			(size 0.519938 1.4986)
			(layers "F.Cu" "F.Mask" "F.Paste")
			(net "GND")
		)
		(pad "280" smd rect
			(at 2.050034 56.524906 270)
			(size 0.519938 1.4986)
			(layers "F.Cu" "F.Mask" "F.Paste")
			(net "M_H_CPU0_SB_DQ<27>")
		)
		(pad "281" smd rect
			(at 2.050034 57.375044 270)
			(size 0.519938 1.4986)
			(layers "F.Cu" "F.Mask" "F.Paste")
			(net "GND")
		)
		(pad "282" smd rect
			(at 2.050034 58.224928 270)
			(size 0.519938 1.4986)
			(layers "F.Cu" "F.Mask" "F.Paste")
			(net "M_H_CPU0_SB_DQS_DN<8>")
		)
		(pad "283" smd rect
			(at 2.050034 59.075066 270)
			(size 0.519938 1.4986)
			(layers "F.Cu" "F.Mask" "F.Paste")
			(net "M_H_CPU0_SB_DQS_DP<8>")
		)
		(pad "284" smd rect
			(at 2.050034 59.92495 270)
			(size 0.519938 1.4986)
			(layers "F.Cu" "F.Mask" "F.Paste")
			(net "GND")
		)
		(pad "285" smd rect
			(at 2.050034 60.775088 270)
			(size 0.519938 1.4986)
			(layers "F.Cu" "F.Mask" "F.Paste")
			(net "M_H_CPU0_SB_DQ<30>")
		)
		(pad "286" smd rect
			(at 2.050034 61.624972 270)
			(size 0.519938 1.4986)
			(layers "F.Cu" "F.Mask" "F.Paste")
			(net "GND")
		)
		(pad "287" smd rect
			(at 2.050034 62.47511 270)
			(size 0.519938 1.4986)
			(layers "F.Cu" "F.Mask" "F.Paste")
			(net "M_H_CPU0_SB_DQ<31>")
		)
		(pad "288" smd rect
			(at 2.050034 63.324994 270)
			(size 0.519938 1.4986)
			(layers "F.Cu" "F.Mask" "F.Paste")
			(net "GND")
		)
		(pad "G1" thru_hole oval
			(at 0 -68.97497)
			(size 2.8194 1.5748)
			(drill oval 2.4384 1.1938)
			(layers "*.Cu" "*.Mask")
			(remove_unused_layers no)
			(net "GND")
			(clearance 0.127)
			(thermal_gap 0.127)
		)
		(pad "G2" thru_hole oval
			(at 0 3.875024)
			(size 2.8194 1.5748)
			(drill oval 2.4384 1.1938)
			(layers "*.Cu" "*.Mask")
			(remove_unused_layers no)
			(net "GND")
			(clearance 0.127)
			(thermal_gap 0.127)
		)
		(pad "G3" thru_hole oval
			(at 0 68.97497)
			(size 2.8194 1.5748)
			(drill oval 2.4384 1.1938)
			(layers "*.Cu" "*.Mask")
			(remove_unused_layers no)
			(net "GND")
			(clearance 0.127)
			(thermal_gap 0.127)
		)
	)
)
